# BASEBOARD_FAB2 (Tioga Pass) — schematic netlist excerpt (pin names and nets, part order shuffled) for the footprints in the layout excerpt that follows; sources: Cadence DE-HDL packaged netlist, KiCad conversion of Wiwynn_Tioga_Pass_MB.brd

R32W2  RES  1.5K 1% CHIP  pkg 0402  page 185 : A = P1V8_M2 ; B = VREF_LMV431_1V42
CT55  CAP  1000PF 50V 10% X7R  pkg 0402LF  page 210 : A = A_TSENSE_PVSA_CPU1 ; B = GND
R7D5  RES  2.26K 1.0% CHIP  pkg 0402  page 181 : A = P3V3_STBY ; B = FM_MB_SLOT_ID0

(kicad_pcb
	(version 20260206)
	(generator "pcbnew")
	(generator_version "10.0")
	(general
		(thickness 1.6)
		(legacy_teardrops no)
	)
	(paper "A4")
	(title_block
		(title "Wiwynn_Tioga_Pass_MB.brd")
		(comment 1 "Tioga Pass / footprints 3108-3110 of 4770")
	)
	(layers
		(0 "F.Cu" signal "TOP")
		(4 "In1.Cu" signal "L2GND")
		(6 "In2.Cu" signal "L3")
		(8 "In3.Cu" signal "L4GND")
		(10 "In4.Cu" signal "L5")
		(12 "In5.Cu" signal "L6GND")
		(14 "In6.Cu" signal "L7VCC")
		(16 "In7.Cu" signal "L8VCC")
		(18 "In8.Cu" signal "L9GND")
		(20 "In9.Cu" signal "L10")
		(22 "In10.Cu" signal "L11GND")
		(24 "In11.Cu" signal "L12")
		(26 "In12.Cu" signal "L13GND")
		(2 "B.Cu" signal "BOTTOM")
		(9 "F.Adhes" user "F.Adhesive")
		(11 "B.Adhes" user "B.Adhesive")
		(13 "F.Paste" user "Package Geometry/Pastemask Top")
		(15 "B.Paste" user "Package Geometry/Pastemask Bottom")
		(5 "F.SilkS" user "Ref Des/Silkscreen Top")
		(7 "B.SilkS" user "Ref Des/Silkscreen Bottom")
		(1 "F.Mask" user "Board Geometry/Soldermask Top")
		(3 "B.Mask" user "Board Geometry/Soldermask Bottom")
		(17 "Dwgs.User" user "User.Drawings")
		(19 "Cmts.User" user "User.Comments")
		(21 "Eco1.User" user "User.Eco1")
		(23 "Eco2.User" user "User.Eco2")
		(25 "Edge.Cuts" user "Board Geometry/Outline")
		(27 "Margin" user)
		(31 "F.CrtYd" user "Package Geometry/Place Bound Top")
		(29 "B.CrtYd" user "Package Geometry/Place Bound Bottom")
		(35 "F.Fab" user "Ref Des/Assembly Top")
		(33 "B.Fab" user "Ref Des/Assembly Bottom")
	)
	(footprint ""
		(layer "B.Cu")
		(at 30.952948 -96.7994)
		(property "Reference" "CT55"
			(at 0.8382 -0.84963 0)
			(unlocked yes)
			(layer "B.SilkS")
			(effects
				(font
					(size 0.7874 0.5842)
					(thickness 0.1524)
				)
				(justify left mirror)
			)
		)
		(property "Value" ""
			(at 0 0 0)
			(layer "B.Fab")
			(effects
				(font
					(size 1.27 1.27)
				)
				(justify mirror)
			)
		)
		(duplicate_pad_numbers_are_jumpers no)
		(fp_poly
			(pts
				(xy -0.3048 -0.1016) (xy -0.3048 0.9906) (xy 0.3048 0.9906) (xy 0.3048 -0.1016)
			)
			(stroke
				(width 0)
				(type default)
			)
			(fill no)
			(layer "B.CrtYd")
		)
		(fp_line
			(start -0.3048 -0.1016)
			(end 0.3048 -0.1016)
			(stroke
				(width 0.1)
				(type default)
			)
			(layer "B.Fab")
		)
		(fp_line
			(start -0.3048 0.9906)
			(end -0.3048 -0.1016)
			(stroke
				(width 0.1)
				(type default)
			)
			(layer "B.Fab")
		)
		(fp_line
			(start 0.3048 -0.1016)
			(end 0.3048 0.9906)
			(stroke
				(width 0.1)
				(type default)
			)
			(layer "B.Fab")
		)
		(fp_line
			(start 0.3048 0.9906)
			(end -0.3048 0.9906)
			(stroke
				(width 0.1)
				(type default)
			)
			(layer "B.Fab")
		)
		(pad "1" smd rect
			(at 0 0 180)
			(size 0.508 0.508)
			(layers "B.Cu" "B.Mask" "B.Paste")
			(net "A_TSENSE_PVSA_CPU1")
		)
		(pad "2" smd rect
			(at 0 0.889 180)
			(size 0.508 0.508)
			(layers "B.Cu" "B.Mask" "B.Paste")
			(net "GND")
		)
		(zone
			(layer "B.Cu")
			(hatch none 0.5)
			(connect_pads
				(clearance 0)
			)
			(min_thickness 0.25)
			(keepout
				(tracks allowed)
				(vias not_allowed)
				(pads allowed)
				(copperpour not_allowed)
				(footprints allowed)
			)
			(placement
				(enabled no)
				(sheetname "")
			)
			(fill
				(thermal_gap 0.5)
				(thermal_bridge_width 0.5)
				(island_removal_mode 0)
			)
			(polygon
				(pts
					(xy 31.206948 -96.5454) (xy 30.698948 -96.5454) (xy 30.698948 -96.1644) (xy 31.206948 -96.1644)
				)
			)
		)
		(zone
			(layer "B.Cu")
			(hatch none 0.5)
			(connect_pads
				(clearance 0)
			)
			(min_thickness 0.25)
			(keepout
				(tracks not_allowed)
				(vias allowed)
				(pads allowed)
				(copperpour not_allowed)
				(footprints allowed)
			)
			(placement
				(enabled no)
				(sheetname "")
			)
			(fill
				(thermal_gap 0.5)
				(thermal_bridge_width 0.5)
				(island_removal_mode 0)
			)
			(polygon
				(pts
					(xy 31.206948 -96.1644) (xy 30.698948 -96.1644) (xy 30.698948 -96.5454) (xy 31.206948 -96.5454)
				)
			)
		)
	)
	(footprint ""
		(layer "B.Cu")
		(at 393.4079 -20.6248 90)
		(property "Reference" "R32W2"
			(at 0.8382 -0.67818 90)
			(unlocked yes)
			(layer "B.SilkS")
			(effects
				(font
					(size 0.4064 0.254)
					(thickness 0.1524)
				)
				(justify left mirror)
			)
		)
		(property "Value" ""
			(at 0 0 90)
			(layer "B.Fab")
			(effects
				(font
					(size 1.27 1.27)
				)
				(justify mirror)
			)
		)
		(duplicate_pad_numbers_are_jumpers no)
		(fp_poly
			(pts
				(xy 0.2794 -0.1016) (xy -0.2794 -0.1016) (xy -0.2794 0.9906) (xy 0.2794 0.9906)
			)
			(stroke
				(width 0)
				(type default)
			)
			(fill no)
			(layer "B.CrtYd")
		)
		(fp_line
			(start 0.2794 -0.1016)
			(end 0.2794 0.9906)
			(stroke
				(width 0.1)
				(type default)
			)
			(layer "B.Fab")
		)
		(fp_line
			(start -0.2794 -0.1016)
			(end 0.2794 -0.1016)
			(stroke
				(width 0.1)
				(type default)
			)
			(layer "B.Fab")
		)
		(fp_line
			(start 0.2794 0.9906)
			(end -0.2794 0.9906)
			(stroke
				(width 0.1)
				(type default)
			)
			(layer "B.Fab")
		)
		(fp_line
			(start -0.2794 0.9906)
			(end -0.2794 -0.1016)
			(stroke
				(width 0.1)
				(type default)
			)
			(layer "B.Fab")
		)
		(pad "1" smd rect
			(at 0 0 270)
			(size 0.508 0.508)
			(layers "B.Cu" "B.Mask" "B.Paste")
			(net "P1V8_M2")
		)
		(pad "2" smd rect
			(at 0 0.889 270)
			(size 0.508 0.508)
			(layers "B.Cu" "B.Mask" "B.Paste")
			(net "VREF_LMV431_1V42")
		)
		(zone
			(layer "B.Cu")
			(hatch none 0.5)
			(connect_pads
				(clearance 0)
			)
			(min_thickness 0.25)
			(keepout
				(tracks allowed)
				(vias not_allowed)
				(pads allowed)
				(copperpour not_allowed)
				(footprints allowed)
			)
			(placement
				(enabled no)
				(sheetname "")
			)
			(fill
				(thermal_gap 0.5)
				(thermal_bridge_width 0.5)
				(island_removal_mode 0)
			)
			(polygon
				(pts
					(xy 393.6619 -20.8788) (xy 393.6619 -20.3708) (xy 394.0429 -20.3708) (xy 394.0429 -20.8788)
				)
			)
		)
		(zone
			(layer "B.Cu")
			(hatch none 0.5)
			(connect_pads
				(clearance 0)
			)
			(min_thickness 0.25)
			(keepout
				(tracks not_allowed)
				(vias allowed)
				(pads allowed)
				(copperpour not_allowed)
				(footprints allowed)
			)
			(placement
				(enabled no)
				(sheetname "")
			)
			(fill
				(thermal_gap 0.5)
				(thermal_bridge_width 0.5)
				(island_removal_mode 0)
			)
			(polygon
				(pts
					(xy 394.0429 -20.8788) (xy 394.0429 -20.3708) (xy 393.6619 -20.3708) (xy 393.6619 -20.8788)
				)
			)
		)
	)
	(footprint ""
		(layer "B.Cu")
		(at 379.222 -87.3125 180)
		(property "Reference" "R7D5"
			(at 0 0 0)
			(layer "B.SilkS")
			(hide yes)
			(effects
				(font
					(size 1.27 1.27)
				)
				(justify mirror)
			)
		)
		(property "Value" ""
			(at 0 0 0)
			(layer "B.Fab")
			(effects
				(font
					(size 1.27 1.27)
				)
				(justify mirror)
			)
		)
		(duplicate_pad_numbers_are_jumpers no)
		(fp_poly
			(pts
				(xy 0.2794 -0.1016) (xy -0.2794 -0.1016) (xy -0.2794 0.9906) (xy 0.2794 0.9906)
			)
			(stroke
				(width 0)
				(type default)
			)
			(fill no)
			(layer "B.CrtYd")
		)
		(fp_line
			(start 0.2794 0.9906)
			(end -0.2794 0.9906)
			(stroke
				(width 0.1)
				(type default)
			)
			(layer "B.Fab")
		)
		(fp_line
			(start 0.2794 -0.1016)
			(end 0.2794 0.9906)
			(stroke
				(width 0.1)
				(type default)
			)
			(layer "B.Fab")
		)
		(fp_line
			(start -0.2794 0.9906)
			(end -0.2794 -0.1016)
			(stroke
				(width 0.1)
				(type default)
			)
			(layer "B.Fab")
		)
		(fp_line
			(start -0.2794 -0.1016)
			(end 0.2794 -0.1016)
			(stroke
				(width 0.1)
				(type default)
			)
			(layer "B.Fab")
		)
		(pad "1" smd rect
			(at 0 0)
			(size 0.508 0.508)
			(layers "B.Cu" "B.Mask" "B.Paste")
			(net "P3V3_STBY")
		)
		(pad "2" smd rect
			(at 0 0.889)
			(size 0.508 0.508)
			(layers "B.Cu" "B.Mask" "B.Paste")
			(net "FM_MB_SLOT_ID0")
		)
		(zone
			(layer "B.Cu")
			(hatch none 0.5)
			(connect_pads
				(clearance 0)
			)
			(min_thickness 0.25)
			(keepout
				(tracks not_allowed)
				(vias allowed)
				(pads allowed)
				(copperpour not_allowed)
				(footprints allowed)
			)
			(placement
				(enabled no)
				(sheetname "")
			)
			(fill
				(thermal_gap 0.5)
				(thermal_bridge_width 0.5)
				(island_removal_mode 0)
			)
			(polygon
				(pts
					(xy 378.968 -87.9475) (xy 379.476 -87.9475) (xy 379.476 -87.5665) (xy 378.968 -87.5665)
				)
			)
		)
		(zone
			(layer "B.Cu")
			(hatch none 0.5)
			(connect_pads
				(clearance 0)
			)
			(min_thickness 0.25)
			(keepout
				(tracks allowed)
				(vias not_allowed)
				(pads allowed)
				(copperpour not_allowed)
				(footprints allowed)
			)
			(placement
				(enabled no)
				(sheetname "")
			)
			(fill
				(thermal_gap 0.5)
				(thermal_bridge_width 0.5)
				(island_removal_mode 0)
			)
			(polygon
				(pts
					(xy 378.968 -87.5665) (xy 379.476 -87.5665) (xy 379.476 -87.9475) (xy 378.968 -87.9475)
				)
			)
		)
	)
)
